# T6G (Grand Teton) — schematic netlist excerpt (pin names and nets, part order shuffled) for the footprints in the layout excerpt that follows; sources: Cadence DE-HDL packaged netlist, KiCad conversion of 04192023_DAF0TMB3IC0_F0TG_MB_C_brd_V02_OCP.brd

PC77  Q_CAP  470PF 50V 10% X7R  pkg 0402  page 200 : A = PVDDIO_P0_TEMP1 ; B = GND
R1557  Q_RES  33 5% CHIP  pkg 0402LF  page 81 : A = ESPI_CPU0_ALERT_R_N ; B = ESPI_CPU0_ALERT_PLD_N

(kicad_pcb
	(version 20260206)
	(generator "pcbnew")
	(generator_version "10.0")
	(general
		(thickness 1.6)
		(legacy_teardrops no)
	)
	(paper "A4")
	(title_block
		(title "04192023_DAF0TMB3IC0_F0TG_MB_C_brd_V02_OCP.brd")
		(comment 1 "Grand Teton / footprints 4235-4236 of 8354")
	)
	(layers
		(0 "F.Cu" signal "TOP")
		(4 "In1.Cu" signal "GND")
		(6 "In2.Cu" signal "IN1")
		(8 "In3.Cu" signal "GND1")
		(10 "In4.Cu" signal "IN2")
		(12 "In5.Cu" signal "GND2")
		(14 "In6.Cu" signal "IN3")
		(16 "In7.Cu" signal "GND3")
		(18 "In8.Cu" signal "VCC")
		(20 "In9.Cu" signal "VCC1")
		(22 "In10.Cu" signal "GND4")
		(24 "In11.Cu" signal "IN4")
		(26 "In12.Cu" signal "GND5")
		(28 "In13.Cu" signal "IN5")
		(30 "In14.Cu" signal "GND6")
		(32 "In15.Cu" signal "IN6")
		(34 "In16.Cu" signal "GND7")
		(2 "B.Cu" signal "BOTTOM")
		(9 "F.Adhes" user "F.Adhesive")
		(11 "B.Adhes" user "B.Adhesive")
		(13 "F.Paste" user "Package Geometry/Pastemask Top")
		(15 "B.Paste" user "Package Geometry/Pastemask Bottom")
		(5 "F.SilkS" user "Ref Des/Silkscreen Top")
		(7 "B.SilkS" user "Ref Des/Silkscreen Bottom")
		(1 "F.Mask" user "Board Geometry/Soldermask Top")
		(3 "B.Mask" user "Board Geometry/Soldermask Bottom")
		(17 "Dwgs.User" user "User.Drawings")
		(19 "Cmts.User" user "User.Comments")
		(21 "Eco1.User" user "User.Eco1")
		(23 "Eco2.User" user "User.Eco2")
		(25 "Edge.Cuts" user "Board Geometry/Outline")
		(27 "Margin" user)
		(31 "F.CrtYd" user "Package Geometry/Place Bound Top")
		(29 "B.CrtYd" user "Package Geometry/Place Bound Bottom")
		(35 "F.Fab" user "Ref Des/Assembly Top")
		(33 "B.Fab" user "Ref Des/Assembly Bottom")
	)
	(footprint ""
		(layer "F.Cu")
		(at 315.802518 -360.289348)
		(property "Reference" "PC77"
			(at 0 0 0)
			(layer "F.SilkS")
			(hide yes)
			(effects
				(font
					(size 1.27 1.27)
				)
			)
		)
		(property "Value" ""
			(at 0 0 0)
			(layer "F.Fab")
			(effects
				(font
					(size 1.27 1.27)
				)
			)
		)
		(duplicate_pad_numbers_are_jumpers no)
		(fp_line
			(start -0.7874 -0.4064)
			(end 0.7874 -0.4064)
			(stroke
				(width 0.1524)
				(type default)
			)
			(layer "F.SilkS")
		)
		(fp_line
			(start -0.7874 0.4064)
			(end -0.7874 -0.4064)
			(stroke
				(width 0.1524)
				(type default)
			)
			(layer "F.SilkS")
		)
		(fp_line
			(start 0.7874 -0.4064)
			(end 0.7874 0.4064)
			(stroke
				(width 0.1524)
				(type default)
			)
			(layer "F.SilkS")
		)
		(fp_line
			(start 0.7874 0.4064)
			(end -0.7874 0.4064)
			(stroke
				(width 0.1524)
				(type default)
			)
			(layer "F.SilkS")
		)
		(fp_line
			(start -0.67945 -0.305054)
			(end -0.12065 -0.305054)
			(stroke
				(width 0.1)
				(type default)
			)
			(layer "F.Fab")
		)
		(fp_line
			(start -0.67945 0.3048)
			(end -0.67945 -0.305054)
			(stroke
				(width 0.1)
				(type default)
			)
			(layer "F.Fab")
		)
		(fp_line
			(start -0.12065 -0.305054)
			(end -0.12065 -0.2794)
			(stroke
				(width 0.1)
				(type default)
			)
			(layer "F.Fab")
		)
		(fp_line
			(start -0.12065 -0.2794)
			(end 0.12065 -0.2794)
			(stroke
				(width 0.1)
				(type default)
			)
			(layer "F.Fab")
		)
		(fp_line
			(start -0.12065 0.2794)
			(end -0.12065 0.3048)
			(stroke
				(width 0.1)
				(type default)
			)
			(layer "F.Fab")
		)
		(fp_line
			(start -0.12065 0.3048)
			(end -0.67945 0.3048)
			(stroke
				(width 0.1)
				(type default)
			)
			(layer "F.Fab")
		)
		(fp_line
			(start 0.120396 0.2794)
			(end -0.12065 0.2794)
			(stroke
				(width 0.1)
				(type default)
			)
			(layer "F.Fab")
		)
		(fp_line
			(start 0.120396 0.3048)
			(end 0.120396 0.2794)
			(stroke
				(width 0.1)
				(type default)
			)
			(layer "F.Fab")
		)
		(fp_line
			(start 0.12065 -0.3048)
			(end 0.67945 -0.3048)
			(stroke
				(width 0.1)
				(type default)
			)
			(layer "F.Fab")
		)
		(fp_line
			(start 0.12065 -0.2794)
			(end 0.12065 -0.3048)
			(stroke
				(width 0.1)
				(type default)
			)
			(layer "F.Fab")
		)
		(fp_line
			(start 0.67945 -0.3048)
			(end 0.67945 0.3048)
			(stroke
				(width 0.1)
				(type default)
			)
			(layer "F.Fab")
		)
		(fp_line
			(start 0.67945 0.3048)
			(end 0.120396 0.3048)
			(stroke
				(width 0.1)
				(type default)
			)
			(layer "F.Fab")
		)
		(pad "1" smd circle
			(at -0.40005 0)
			(size 0 0)
			(layers "F.Cu" "F.Mask" "F.Paste")
			(net "PVDDIO_P0_TEMP1")
		)
		(pad "2" smd circle
			(at 0.40005 0)
			(size 0 0)
			(layers "F.Cu" "F.Mask" "F.Paste")
			(net "GND")
		)
	)
	(footprint ""
		(layer "F.Cu")
		(at 185.039 -137.632948 90)
		(property "Reference" "R1557"
			(at 0 0 90)
			(layer "F.SilkS")
			(hide yes)
			(effects
				(font
					(size 1.27 1.27)
				)
			)
		)
		(property "Value" ""
			(at 0 0 90)
			(layer "F.Fab")
			(effects
				(font
					(size 1.27 1.27)
				)
			)
		)
		(duplicate_pad_numbers_are_jumpers no)
		(fp_line
			(start 0.7874 -0.4064)
			(end 0.7874 0.4064)
			(stroke
				(width 0.1524)
				(type default)
			)
			(layer "F.SilkS")
		)
		(fp_line
			(start -0.7874 -0.4064)
			(end 0.7874 -0.4064)
			(stroke
				(width 0.1524)
				(type default)
			)
			(layer "F.SilkS")
		)
		(fp_line
			(start 0.7874 0.4064)
			(end -0.7874 0.4064)
			(stroke
				(width 0.1524)
				(type default)
			)
			(layer "F.SilkS")
		)
		(fp_line
			(start -0.7874 0.4064)
			(end -0.7874 -0.4064)
			(stroke
				(width 0.1524)
				(type default)
			)
			(layer "F.SilkS")
		)
		(fp_line
			(start -0.12065 -0.305054)
			(end -0.12065 -0.2794)
			(stroke
				(width 0.1)
				(type default)
			)
			(layer "F.Fab")
		)
		(fp_line
			(start -0.67945 -0.305054)
			(end -0.12065 -0.305054)
			(stroke
				(width 0.1)
				(type default)
			)
			(layer "F.Fab")
		)
		(fp_line
			(start 0.67945 -0.3048)
			(end 0.67945 0.3048)
			(stroke
				(width 0.1)
				(type default)
			)
			(layer "F.Fab")
		)
		(fp_line
			(start 0.12065 -0.3048)
			(end 0.67945 -0.3048)
			(stroke
				(width 0.1)
				(type default)
			)
			(layer "F.Fab")
		)
		(fp_line
			(start 0.12065 -0.2794)
			(end 0.12065 -0.3048)
			(stroke
				(width 0.1)
				(type default)
			)
			(layer "F.Fab")
		)
		(fp_line
			(start -0.12065 -0.2794)
			(end 0.12065 -0.2794)
			(stroke
				(width 0.1)
				(type default)
			)
			(layer "F.Fab")
		)
		(fp_line
			(start 0.120396 0.2794)
			(end -0.12065 0.2794)
			(stroke
				(width 0.1)
				(type default)
			)
			(layer "F.Fab")
		)
		(fp_line
			(start -0.12065 0.2794)
			(end -0.12065 0.3048)
			(stroke
				(width 0.1)
				(type default)
			)
			(layer "F.Fab")
		)
		(fp_line
			(start 0.67945 0.3048)
			(end 0.120396 0.3048)
			(stroke
				(width 0.1)
				(type default)
			)
			(layer "F.Fab")
		)
		(fp_line
			(start 0.120396 0.3048)
			(end 0.120396 0.2794)
			(stroke
				(width 0.1)
				(type default)
			)
			(layer "F.Fab")
		)
		(fp_line
			(start -0.12065 0.3048)
			(end -0.67945 0.3048)
			(stroke
				(width 0.1)
				(type default)
			)
			(layer "F.Fab")
		)
		(fp_line
			(start -0.67945 0.3048)
			(end -0.67945 -0.305054)
			(stroke
				(width 0.1)
				(type default)
			)
			(layer "F.Fab")
		)
		(pad "1" smd circle
			(at -0.40005 0 90)
			(size 0 0)
			(layers "F.Cu" "F.Mask" "F.Paste")
			(net "ESPI_CPU0_ALERT_R_N")
		)
		(pad "2" smd circle
			(at 0.40005 0 90)
			(size 0 0)
			(layers "F.Cu" "F.Mask" "F.Paste")
			(net "ESPI_CPU0_ALERT_PLD_N")
		)
	)
)
